FILE_TYPE = CONNECTIVITY;
{Allegro Design Entry HDL 17.4-2019 S026 (4007227) 1/17/2022}
"PAGE_NUMBER" = 34;
0"NC";
1"GND\g";
2"GND\g";
3"GND\g";
4"GND\g";
5"P1V8_AUX\g";
6"GND\g";
7"GND\g";
8"PVDD18_S5_P0\g";
9"SMB_CPU0_4_SDA";
10"SMB_CPU0_4_SCL";
11"P3V3_AUX\g";
12"PVDD18_S5_P0\g";
13"P3V3_AUX\g";
14"PVDD18_S5_P0\g";
15"SMB_CPU0_4_XLTR_SDA";
16"SMB_CPU0_4_XLTR_SCL";
17"TP_U27_EN";
18"SMB_CPU0_4_SCL";
19"SMB_CPU0_4_SDA";
20"FM_BIOS_POST_CMPLT_BUF_N";
21"SMB_CPU0_4_XLTR_SDA";
22"FM_BIOS_POST_CMPLT_BUF_R1_N";
23"SMB_CPU0_4_XLTR_SCL";
24"FM_BIOS_POST_CMPLT_N";
%"Q_RES"
"1","(-1625,4925)","0","pure_quanta","I106";
;
LOCATION"R495"
$SEC"1"
CDS_SEC"1"
VALUE"4.7K"
MATERIAL"CHIP"
PACK_TYPE"0402LF"
TOLERANCE"5%"
WATTAGE"1/16W"
CDS_LIB"pure_quanta"
PART_NUMBER"CS24702JB10";
"B"
$PN"2"10;
"A"
$PN"1"8;
%"Q_RES"
"1","(-1625,4850)","0","pure_quanta","I107";
;
LOCATION"R498"
$SEC"1"
CDS_SEC"1"
VALUE"2.2K"
MATERIAL"CHIP"
PACK_TYPE"0402LF"
TOLERANCE"5%"
WATTAGE"1/16W"
CDS_LIB"pure_quanta"
PART_NUMBER"CS22202JB07";
"B"
$PN"2"9;
"A"
$PN"1"8;
%"UNIVERSAL_POWER"
"1","(-2025,5400)","2","pure_quanta_power","I108";
;
HDL_POWER"PVDD18_S5_P0"
CDS_LIB"pure_quanta_power";
"A"8;
%"UNIVERSAL_GND"
"1","(-4600,2250)","0","pure_quanta_power","I123";
;
CDS_LIB"pure_quanta_power"
HDL_POWER"GND";
"A"1;
%"Q_CAP"
"1","(-4600,2450)","0","pure_quanta","I124";
;
LOCATION"C5000"
$SEC"1"
CDS_SEC"1"
MATERIAL"X7R"
VOLTAGE"50V"
TOLERANCE"5%"
VALUE"1000PF"
PACK_TYPE"0402"
CDS_LIB"pure_quanta"
PART_NUMBER"TMP_QCH21006JB10";
"B"
$PN"2"1;
"A"
$PN"1"20;
%"Q_RES"
"1","(-5025,2725)","0","pure_quanta","I125";
;
LOCATION"R6100"
$SEC"1"
CDS_SEC"1"
VALUE"49.9"
CDS_LIB"pure_quanta"
WATTAGE"1/16W"
MATERIAL"CHIP"
PACK_TYPE"0402LF"
TOLERANCE"1%"
PART_NUMBER"CS04992FB07";
"B"
$PN"2"20;
"A"
$PN"1"22;
%"PCA9617ADP"
"1","(-7200,5575)","0","pure_quanta","I18";
;
LOCATION"U27"
$SEC"1"
CDS_SEC"1"
PART_TYPE"SMLF"
MATERIAL"IC"
VALUE"PCA9617ADP"
NEEDS_NO_SIZE"TRUE"
CDS_LMAN_SYM_OUTLINE"-275,300,275,-300"
CDS_LIB"pure_quanta"
PART_NUMBER"AL009617K02";
"GND"
$PN"4"2;
"SCLB"
$PN"7"16;
"SDAB"
$PN"6"15;
"SDAA"
$PN"3"19;
"SCLA"
$PN"2"18;
"VCCB"
$PN"8"13;
"VCCA"
$PN"1"12;
"EN"
$PN"5"17;
%"UNIVERSAL_POWER"
"1","(-2025,6475)","2","pure_quanta_power","I3";
;
HDL_POWER"P3V3_AUX"
CDS_LIB"pure_quanta_power";
"A"11;
%"Q_RES"
"1","(-1675,6000)","0","pure_quanta","I4";
;
LOCATION"R499"
$SEC"1"
CDS_SEC"1"
VALUE"4.7K"
PACK_TYPE"0402LF"
TOLERANCE"5%"
MATERIAL"CHIP"
WATTAGE"1/16W"
CDS_LIB"pure_quanta"
PART_NUMBER"CS24702JB10";
"B"
$PN"2"23;
"A"
$PN"1"11;
%"UNIVERSAL_GND"
"1","(-7775,5175)","0","pure_quanta_power","I40";
;
CDS_LIB"pure_quanta_power"
HDL_POWER"GND";
"A"2;
%"UNIVERSAL_POWER"
"1","(-7700,6300)","2","pure_quanta_power","I43";
;
HDL_POWER"PVDD18_S5_P0"
CDS_LIB"pure_quanta_power";
"A"12;
%"Q_CAP"
"1","(-7875,6025)","0","pure_quanta","I44";
;
LOCATION"C42"
$SEC"1"
CDS_SEC"1"
MATERIAL"X7R"
TOLERANCE"10%"
VALUE"0.1UF"
VOLTAGE"25V"
PACK_TYPE"0402"
CDS_LIB"pure_quanta"
PART_NUMBER"CH4104K1B00";
"B"
$PN"2"3;
"A"
$PN"1"12;
%"UNIVERSAL_GND"
"1","(-7875,5825)","0","pure_quanta_power","I45";
;
CDS_LIB"pure_quanta_power"
HDL_POWER"GND";
"A"3;
%"UNIVERSAL_POWER"
"1","(-6625,6350)","2","pure_quanta_power","I46";
;
HDL_POWER"P3V3_AUX"
CDS_LIB"pure_quanta_power";
"A"13;
%"Q_CAP"
"1","(-6550,6025)","0","pure_quanta","I47";
;
LOCATION"C43"
$SEC"1"
CDS_SEC"1"
TOLERANCE"10%"
VOLTAGE"25V"
MATERIAL"X7R"
VALUE"0.1UF"
PACK_TYPE"0402"
CDS_LIB"pure_quanta"
PART_NUMBER"CH4104K1B00";
"B"
$PN"2"4;
"A"
$PN"1"13;
%"UNIVERSAL_GND"
"1","(-6550,5825)","0","pure_quanta_power","I48";
;
CDS_LIB"pure_quanta_power"
HDL_POWER"GND";
"A"4;
%"Q_RES"
"1","(-1675,5925)","0","pure_quanta","I5";
;
LOCATION"R590"
$SEC"1"
CDS_SEC"1"
VALUE"4.7K"
PACK_TYPE"0402LF"
TOLERANCE"5%"
MATERIAL"CHIP"
WATTAGE"1/16W"
CDS_LIB"pure_quanta"
PART_NUMBER"CS24702JB10";
"B"
$PN"2"21;
"A"
$PN"1"11;
%"Q_RES"
"2","(-5400,2975)","0","pure_quanta","I53";
;
LOCATION"R943"
$SEC"1"
CDS_SEC"1"
VALUE"4.7K"
TOLERANCE"5%"
MATERIAL"CHIP"
WATTAGE"1/16W"
PACK_TYPE"0402LF"
BOM_COST"OCP3.0 "
CDS_LIB"pure_quanta"
PART_NUMBER"CS24702JB10";
"A"
$PN"1"5;
"B"
$PN"2"22;
%"UNIVERSAL_POWER"
"1","(-5400,3250)","0","pure_quanta_power","I54";
;
HDL_POWER"P1V8_AUX"
BOM_COST"OCP3.0 "
CDS_LIB"pure_quanta_power";
"A"5;
%"SN74LVC1G07DBVR"
"1","(-6350,2725)","0","pure_quanta","I55";
;
LOCATION"U101"
$SEC"1"
CDS_SEC"1"
MATERIAL"IC"
PACK_TYPE"SMLF"
VALUE"SN74LVC1G07DBVR"
CDS_LIB"pure_quanta"
NEEDS_NO_SIZE"TRUE"
PART_NUMBER"AL1G0007024";
"NC"
$PN"1"0;
"Y"
$PN"4"22;
"GND"
$PN"3"6;
"A"
$PN"2"24;
"VCC"
$PN"5"14;
%"UNIVERSAL_GND"
"1","(-6600,2450)","0","pure_quanta_power","I56";
;
BOM_COST"OCP3.0 "
CDS_LIB"pure_quanta_power"
HDL_POWER"GND";
"A"6;
%"UNIVERSAL_GND"
"1","(-6950,2850)","0","pure_quanta_power","I58";
;
BOM_COST"OCP3.0 "
CDS_LIB"pure_quanta_power"
HDL_POWER"GND";
"A"7;
%"Q_CAP"
"1","(-6950,3050)","0","pure_quanta","I59";
;
LOCATION"C226"
$SEC"1"
CDS_SEC"1"
PACK_TYPE"0402"
MATERIAL"X7R"
TOLERANCE"10%"
VALUE"0.1UF"
VOLTAGE"25V"
CDS_LIB"pure_quanta"
BOM_COST"OCP3.0 "
PART_NUMBER"CH4104K1B00";
"B"
$PN"2"7;
"A"
$PN"1"14;
%"Q_RES"
"2","(-7075,3050)","2","pure_quanta","I60";
;
LOCATION"R942"
$SEC"1"
CDS_SEC"1"
PACK_TYPE"0402LF"
VALUE"4.7K"
TOLERANCE"5%"
MATERIAL"CHIP"
WATTAGE"1/16W"
BOM_COST"OCP3.0 "
CDS_LIB"pure_quanta"
PART_NUMBER"CS24702JB10";
"A"
$PN"1"14;
"B"
$PN"2"24;
%"P1V0"
"1","(-6950,3350)","0","pure_quanta_power","I62";
;
HDL_POWER"PVDD18_S5_P0"
CDS_LIB"pure_quanta_power";
"A"14;
END.
